;LEADER: 12 
;HEADER: 
;CODE  : ASCII 
;FILE  : 9127_F0T_Expander_BD_F_v02_0110_1240-bd-1-15.drl for backdrilling ... from layer TOP to layer GND6
;DESIGN: 9127_F0T_Expander_BD_F_v02_0110_1240.brd
;MUST-NOT-CUT-LAYER = IN6,  MAX_DRILL_DEPTH = 109.25 MILS,  MFG_STUB_LENGTH = 0.00 MILS
;   BackdrillSize 1. = 17.700000 Tolerance = +0.000000/-0.000000 NON_PLATED MILS Quantity = 8
%
G90
X1011187Y-0040126
X1011187Y-0043526
X1225405Y-0082678
X1225405Y-0079278
X1230761Y-0040228
X1081187Y-0082706
X1081187Y-0079306
X1230761Y-0043628
M30
